(kicad_pcb
	(version 20260206)
	(generator "pcbnew")
	(generator_version "10.0")
	(general
		(thickness 1.6)
		(legacy_teardrops no)
	)
	(paper "A4")
	(title_block
		(title "Wiwynn_Tioga_Pass_MB.brd")
		(comment 1 "Tioga Pass / footprint 2035 of 4770 (U8D7), pads 218-256 of 256")
	)
	(layers
		(0 "F.Cu" signal "TOP")
		(4 "In1.Cu" signal "L2GND")
		(6 "In2.Cu" signal "L3")
		(8 "In3.Cu" signal "L4GND")
		(10 "In4.Cu" signal "L5")
		(12 "In5.Cu" signal "L6GND")
		(14 "In6.Cu" signal "L7VCC")
		(16 "In7.Cu" signal "L8VCC")
		(18 "In8.Cu" signal "L9GND")
		(20 "In9.Cu" signal "L10")
		(22 "In10.Cu" signal "L11GND")
		(24 "In11.Cu" signal "L12")
		(26 "In12.Cu" signal "L13GND")
		(2 "B.Cu" signal "BOTTOM")
		(9 "F.Adhes" user "F.Adhesive")
		(11 "B.Adhes" user "B.Adhesive")
		(13 "F.Paste" user "Package Geometry/Pastemask Top")
		(15 "B.Paste" user "Package Geometry/Pastemask Bottom")
		(5 "F.SilkS" user "Ref Des/Silkscreen Top")
		(7 "B.SilkS" user "Ref Des/Silkscreen Bottom")
		(1 "F.Mask" user "Board Geometry/Soldermask Top")
		(3 "B.Mask" user "Board Geometry/Soldermask Bottom")
		(17 "Dwgs.User" user "User.Drawings")
		(19 "Cmts.User" user "User.Comments")
		(21 "Eco1.User" user "User.Eco1")
		(23 "Eco2.User" user "User.Eco2")
		(25 "Edge.Cuts" user "Board Geometry/Outline")
		(27 "Margin" user)
		(31 "F.CrtYd" user "Package Geometry/Place Bound Top")
		(29 "B.CrtYd" user "Package Geometry/Place Bound Bottom")
		(35 "F.Fab" user "Ref Des/Assembly Top")
		(33 "B.Fab" user "Ref Des/Assembly Bottom")
	)
	(footprint ""
		(layer "F.Cu")
		(at 372.745 -74.295 180)
		(property "Reference" "U8D7"
			(at -0.635 -8.28167 0)
			(unlocked yes)
			(layer "F.SilkS")
			(effects
				(font
					(size 0.7874 0.5842)
					(thickness 0.1524)
				)
			)
		)
		(property "Value" ""
			(at 0 0 180)
			(layer "F.Fab")
			(effects
				(font
					(size 1.27 1.27)
				)
			)
		)
		(duplicate_pad_numbers_are_jumpers no)
		(pad "P10" smd circle
			(at 1.199896 4.400042 180)
			(size 0.3556 0.3556)
			(layers "F.Cu" "F.Mask" "F.Paste")
			(net "RST_CD_CPU1_POR_N")
		)
		(pad "P11" smd circle
			(at 1.999996 4.400042 180)
			(size 0.3556 0.3556)
			(layers "F.Cu" "F.Mask" "F.Paste")
			(net "FM_UARTSW_MSB_N")
		)
		(pad "P12" smd circle
			(at 2.800096 4.400042 180)
			(size 0.3556 0.3556)
			(layers "F.Cu" "F.Mask" "F.Paste")
			(net "FM_CPU1_PKGID1")
		)
		(pad "P13" smd circle
			(at 3.599942 4.400042 180)
			(size 0.3556 0.3556)
			(layers "F.Cu" "F.Mask" "F.Paste")
			(net "TP_CPLD1_PB25B_SI_SISPI")
		)
		(pad "P14" smd circle
			(at 4.400042 4.400042 180)
			(size 0.3556 0.3556)
			(layers "F.Cu" "F.Mask" "F.Paste")
			(net "GND")
		)
		(pad "P15" smd circle
			(at 5.199888 4.400042 180)
			(size 0.3556 0.3556)
			(layers "F.Cu" "F.Mask" "F.Paste")
			(net "FM_PVPP_CPU0_EN")
		)
		(pad "P16" smd circle
			(at 5.999988 4.400042 180)
			(size 0.3556 0.3556)
			(layers "F.Cu" "F.Mask" "F.Paste")
			(net "FM_PVPP_CPU1_EN")
		)
		(pad "R1" smd circle
			(at -5.999988 5.199888 180)
			(size 0.3556 0.3556)
			(layers "F.Cu" "F.Mask" "F.Paste")
			(net "FM_BMC_CPLD_GPO")
		)
		(pad "R2" smd circle
			(at -5.199888 5.199888 180)
			(size 0.3556 0.3556)
			(layers "F.Cu" "F.Mask" "F.Paste")
			(net "GND")
		)
		(pad "R3" smd circle
			(at -4.400042 5.199888 180)
			(size 0.3556 0.3556)
			(layers "F.Cu" "F.Mask" "F.Paste")
			(net "FM_CPU0_RC_EN")
		)
		(pad "R4" smd circle
			(at -3.599942 5.199888 180)
			(size 0.3556 0.3556)
			(layers "F.Cu" "F.Mask" "F.Paste")
			(net "FM_BMC_CPLD_MP_RST_N")
		)
		(pad "R5" smd circle
			(at -2.800096 5.199888 180)
			(size 0.3556 0.3556)
			(layers "F.Cu" "F.Mask" "F.Paste")
			(net "TP_CPLD1_PB5A_CSSPIN")
		)
		(pad "R6" smd circle
			(at -1.999996 5.199888 180)
			(size 0.3556 0.3556)
			(layers "F.Cu" "F.Mask" "F.Paste")
			(net "RST_PCIE_M2_DEV_N")
		)
		(pad "R7" smd circle
			(at -1.199896 5.199888 180)
			(size 0.3556 0.3556)
			(layers "F.Cu" "F.Mask" "F.Paste")
			(net "PWRGD_PVTT_CPU1")
		)
		(pad "R8" smd circle
			(at -0.40005 5.199888 180)
			(size 0.3556 0.3556)
			(layers "F.Cu" "F.Mask" "F.Paste")
			(net "FM_CPLD_USB_P0_EN_N")
		)
		(pad "R9" smd circle
			(at 0.40005 5.199888 180)
			(size 0.3556 0.3556)
			(layers "F.Cu" "F.Mask" "F.Paste")
			(net "FM_UARTSW_LSB_N")
		)
		(pad "R10" smd circle
			(at 1.199896 5.199888 180)
			(size 0.3556 0.3556)
			(layers "F.Cu" "F.Mask" "F.Paste")
			(net "RST_CPU0_LVC3_R1_N")
		)
		(pad "R11" smd circle
			(at 1.999996 5.199888 180)
			(size 0.3556 0.3556)
			(layers "F.Cu" "F.Mask" "F.Paste")
			(net "FM_DB1200ZL_BCLKS_EN_N")
		)
		(pad "R12" smd circle
			(at 2.800096 5.199888 180)
			(size 0.3556 0.3556)
			(layers "F.Cu" "F.Mask" "F.Paste")
			(net "FM_CPU1_PKGID0")
		)
		(pad "R13" smd circle
			(at 3.599942 5.199888 180)
			(size 0.3556 0.3556)
			(layers "F.Cu" "F.Mask" "F.Paste")
			(net "FM_CPU0_VRM_OSC_EN")
		)
		(pad "R14" smd circle
			(at 4.400042 5.199888 180)
			(size 0.3556 0.3556)
			(layers "F.Cu" "F.Mask" "F.Paste")
			(net "FM_CPU_CATERR_LVT3_N")
		)
		(pad "R15" smd circle
			(at 5.199888 5.199888 180)
			(size 0.3556 0.3556)
			(layers "F.Cu" "F.Mask" "F.Paste")
			(net "GND")
		)
		(pad "R16" smd circle
			(at 5.999988 5.199888 180)
			(size 0.3556 0.3556)
			(layers "F.Cu" "F.Mask" "F.Paste")
			(net "FM_P12V_MAIN_SW_EN")
		)
		(pad "T1" smd circle
			(at -5.999988 5.999988 180)
			(size 0.3556 0.3556)
			(layers "F.Cu" "F.Mask" "F.Paste")
			(net "P3V3_STBY")
		)
		(pad "T2" smd circle
			(at -5.199888 5.999988 180)
			(size 0.3556 0.3556)
			(layers "F.Cu" "F.Mask" "F.Paste")
			(net "FM_ADR_MODE_SEL")
		)
		(pad "T3" smd circle
			(at -4.400042 5.999988 180)
			(size 0.3556 0.3556)
			(layers "F.Cu" "F.Mask" "F.Paste")
			(net "FM_DIS_ADR_DLY")
		)
		(pad "T4" smd circle
			(at -3.599942 5.999988 180)
			(size 0.3556 0.3556)
			(layers "F.Cu" "F.Mask" "F.Paste")
			(net "PWRGD_PVSA_CPU1")
		)
		(pad "T5" smd circle
			(at -2.800096 5.999988 180)
			(size 0.3556 0.3556)
			(layers "F.Cu" "F.Mask" "F.Paste")
			(net "PWRGD_PVCCIOMCP_CPU1")
		)
		(pad "T6" smd circle
			(at -1.999996 5.999988 180)
			(size 0.3556 0.3556)
			(layers "F.Cu" "F.Mask" "F.Paste")
			(net "TP_CPLD1_PB8B_SO_SPISO")
		)
		(pad "T7" smd circle
			(at -1.199896 5.999988 180)
			(size 0.3556 0.3556)
			(layers "F.Cu" "F.Mask" "F.Paste")
			(net "FM_PVCCIO_CPU1_EN")
		)
		(pad "T8" smd circle
			(at -0.40005 5.999988 180)
			(size 0.3556 0.3556)
			(layers "F.Cu" "F.Mask" "F.Paste")
			(net "FM_CPLD_DBG_PWR_EN_N")
		)
		(pad "T9" smd circle
			(at 0.40005 5.999988 180)
			(size 0.3556 0.3556)
			(layers "F.Cu" "F.Mask" "F.Paste")
			(net "TP_CPLD1_PB16A_PCLKT2_1")
		)
		(pad "T10" smd circle
			(at 1.199896 5.999988 180)
			(size 0.3556 0.3556)
			(layers "F.Cu" "F.Mask" "F.Paste")
			(net "FM_156M_CPU0_BRD_OSC_EN")
		)
		(pad "T11" smd circle
			(at 1.999996 5.999988 180)
			(size 0.3556 0.3556)
			(layers "F.Cu" "F.Mask" "F.Paste")
			(net "FM_CPU1_PKGID2")
		)
		(pad "T12" smd circle
			(at 2.800096 5.999988 180)
			(size 0.3556 0.3556)
			(layers "F.Cu" "F.Mask" "F.Paste")
			(net "FM_CPU1_SKTOCC_LVT3_N")
		)
		(pad "T13" smd circle
			(at 3.599942 5.999988 180)
			(size 0.3556 0.3556)
			(layers "F.Cu" "F.Mask" "F.Paste")
			(net "FM_CPU_MSMI_LVT3_N")
		)
		(pad "T14" smd circle
			(at 4.400042 5.999988 180)
			(size 0.3556 0.3556)
			(layers "F.Cu" "F.Mask" "F.Paste")
			(net "FM_CPU0_SKTOCC_LVT3_N")
		)
		(pad "T15" smd circle
			(at 5.199888 5.999988 180)
			(size 0.3556 0.3556)
			(layers "F.Cu" "F.Mask" "F.Paste")
			(net "PWRGD_DRAMPWRGD")
		)
		(pad "T16" smd circle
			(at 5.999988 5.999988 180)
			(size 0.3556 0.3556)
			(layers "F.Cu" "F.Mask" "F.Paste")
			(net "P3V3_STBY")
		)
	)
)
